G04*
G04 #@! TF.GenerationSoftware,Altium Limited,Altium Designer,23.7.1 (13)*
G04*
G04 Layer_Color=32768*
%FSLAX25Y25*%
%MOIN*%
G70*
G04*
G04 #@! TF.SameCoordinates,AF00DCEB-AC48-4C7C-91EA-99F42E284231*
G04*
G04*
G04 #@! TF.FilePolarity,Positive*
G04*
G01*
G75*
%ADD19C,0.00600*%
%ADD23C,0.00394*%
%ADD291C,0.00197*%
%ADD292C,0.00400*%
G36*
X87757Y-5830D02*
Y-979D01*
X92608D01*
D01*
X108507D01*
D01*
X113357D01*
Y-5830D01*
D01*
Y-21729D01*
D01*
Y-26579D01*
X108507D01*
D01*
X92608D01*
D01*
X87757D01*
Y-21729D01*
D01*
Y-5830D01*
D01*
D02*
G37*
G36*
X146335Y-6706D02*
X143687D01*
Y-4059D01*
X142487D01*
Y4846D01*
X143687D01*
Y7494D01*
X146335D01*
Y8694D01*
X155240D01*
Y7494D01*
X157887D01*
Y4846D01*
X159087D01*
Y-4059D01*
X157887D01*
Y-6706D01*
X155240D01*
Y-7906D01*
X146335D01*
Y-6706D01*
D02*
G37*
G36*
X473894Y-311037D02*
X471246D01*
Y-308390D01*
X470047D01*
Y-299484D01*
X471246D01*
Y-296837D01*
X473894D01*
Y-295637D01*
X482799D01*
Y-296837D01*
X485447D01*
Y-299484D01*
X486647D01*
Y-308390D01*
X485447D01*
Y-311037D01*
X482799D01*
Y-312237D01*
X473894D01*
Y-311037D01*
D02*
G37*
G36*
X429996Y-103243D02*
X434847D01*
Y-108094D01*
D01*
Y-123993D01*
D01*
Y-128843D01*
X429996D01*
D01*
X414098D01*
D01*
X409247D01*
Y-123993D01*
D01*
Y-108094D01*
D01*
Y-103243D01*
X414098D01*
D01*
X429996D01*
D01*
D02*
G37*
G36*
X552548Y-22414D02*
X578948D01*
Y-24864D01*
X586048D01*
Y-48364D01*
X578948D01*
Y-50814D01*
X552548D01*
Y-48464D01*
X539548D01*
Y-24764D01*
X552548D01*
Y-22414D01*
D02*
G37*
D19*
X471246Y-311037D02*
X473894D01*
Y-312237D02*
Y-311037D01*
Y-312237D02*
X482799D01*
Y-311037D01*
X485447D01*
Y-308390D01*
X486647D01*
Y-299484D01*
X485447D02*
X486647D01*
X485447D02*
Y-296837D01*
X482799D02*
X485447D01*
X482799D02*
Y-295637D01*
X473894D02*
X482799D01*
X473894Y-296837D02*
Y-295637D01*
X471246Y-296837D02*
X473894D01*
X471246Y-299484D02*
Y-296837D01*
X470047Y-299484D02*
X471246D01*
X470047Y-308390D02*
Y-299484D01*
Y-308390D02*
X471246D01*
Y-311037D02*
Y-308390D01*
X143687Y-6706D02*
X146335D01*
Y-7906D02*
Y-6706D01*
Y-7906D02*
X155240D01*
Y-6706D01*
X157887D01*
Y-4059D01*
X159087D01*
Y4846D01*
X157887D02*
X159087D01*
X157887D02*
Y7494D01*
X155240D02*
X157887D01*
X155240D02*
Y8694D01*
X146335D02*
X155240D01*
X146335Y7494D02*
Y8694D01*
X143687Y7494D02*
X146335D01*
X143687Y4846D02*
Y7494D01*
X142487Y4846D02*
X143687D01*
X142487Y-4059D02*
Y4846D01*
Y-4059D02*
X143687D01*
Y-6706D02*
Y-4059D01*
X552548Y-22414D02*
X578948D01*
Y-24864D02*
Y-22414D01*
Y-24864D02*
X586048D01*
Y-48364D02*
Y-24864D01*
X578948Y-48364D02*
X586048D01*
X578948Y-50814D02*
Y-48364D01*
X552548Y-50814D02*
X578948D01*
X552548D02*
Y-48464D01*
X539548D02*
X552548D01*
X539548D02*
Y-24764D01*
X552548D01*
Y-22414D01*
X87757Y-5830D02*
Y-979D01*
Y-21729D02*
Y-5830D01*
Y-26579D02*
Y-21729D01*
Y-26579D02*
X92608D01*
X108507D01*
X113357D01*
Y-21729D01*
Y-5830D01*
Y-979D01*
X108507D02*
X113357D01*
X92608D02*
X108507D01*
X87757D02*
X92608D01*
X429996Y-103243D02*
X434847D01*
X414098D02*
X429996D01*
X409247D02*
X414098D01*
X409247Y-108094D02*
Y-103243D01*
Y-123993D02*
Y-108094D01*
Y-128843D02*
Y-123993D01*
Y-128843D02*
X414098D01*
X429996D01*
X434847D01*
Y-123993D01*
Y-108094D01*
Y-103243D01*
D23*
X44319Y-154365D02*
X46484D01*
X45401Y-155448D02*
Y-153283D01*
X442520Y-154331D02*
X444882D01*
X443701Y-155512D02*
Y-153150D01*
X437303Y-147244D02*
Y-144882D01*
X436122Y-146063D02*
X438484D01*
X441732Y-147244D02*
Y-144882D01*
X440551Y-146063D02*
X442913D01*
X452854Y-147244D02*
Y-144882D01*
X451673Y-146063D02*
X454035D01*
X68898Y787D02*
X71260D01*
X70079Y-394D02*
Y1969D01*
X53740Y-5709D02*
X56102D01*
X54921Y-6890D02*
Y-4528D01*
X534235Y-283563D02*
Y-281398D01*
X533152Y-282481D02*
X535318D01*
X566995Y-273924D02*
Y-271759D01*
X565912Y-272841D02*
X568078D01*
X541043Y-279921D02*
X543209D01*
X542126Y-281004D02*
Y-278839D01*
X556759Y-276680D02*
Y-274515D01*
X555676Y-275597D02*
X557841D01*
X110630Y-31398D02*
Y-29232D01*
X109547Y-30315D02*
X111713D01*
X111024Y-24705D02*
Y-22539D01*
X109941Y-23622D02*
X112106D01*
X84981Y-125778D02*
Y-121841D01*
X83013Y-123809D02*
X86950D01*
X59489Y-133652D02*
X63229D01*
X61359Y-135522D02*
Y-131781D01*
X49351Y-116624D02*
Y-114459D01*
X48269Y-115541D02*
X50434D01*
X61950Y-123809D02*
X65887D01*
X63918Y-125778D02*
Y-121841D01*
X49351Y-112687D02*
Y-110522D01*
X48269Y-111604D02*
X50434D01*
X49351Y-109144D02*
Y-106978D01*
X48269Y-108061D02*
X50434D01*
X129310Y-116147D02*
X133247D01*
X131279Y-118115D02*
Y-114178D01*
X129246Y-110462D02*
X133184D01*
X131215Y-112431D02*
Y-108494D01*
X253082Y-119789D02*
Y-115852D01*
X251113Y-117821D02*
X255050D01*
X268307Y-128937D02*
X272244D01*
X270276Y-130905D02*
Y-126969D01*
Y-143110D02*
Y-139173D01*
X268307Y-141142D02*
X272244D01*
X270276Y-154528D02*
Y-150591D01*
X268307Y-152559D02*
X272244D01*
X158205Y-121457D02*
X160371D01*
X159288Y-122539D02*
Y-120374D01*
X386614Y-236221D02*
Y-232283D01*
X384646Y-234252D02*
X388583D01*
X614173Y-281988D02*
Y-278051D01*
X612205Y-280020D02*
X616142D01*
X135433Y-10925D02*
Y-8760D01*
X134350Y-9843D02*
X136516D01*
X583858Y-215256D02*
Y-213091D01*
X582776Y-214173D02*
X584941D01*
X580807Y-241831D02*
X582972D01*
X581890Y-242913D02*
Y-240748D01*
X587894Y-185827D02*
X590059D01*
X588976Y-186909D02*
Y-184744D01*
X589764Y-178248D02*
Y-176083D01*
X588681Y-177165D02*
X590846D01*
X589730Y-161304D02*
Y-159139D01*
X588648Y-160221D02*
X590813D01*
X605512Y-168898D02*
X609449D01*
X607480Y-170866D02*
Y-166929D01*
X596161Y-144488D02*
X598327D01*
X597244Y-145571D02*
Y-143405D01*
X533580Y-256004D02*
X535942D01*
X534761Y-257185D02*
Y-254823D01*
X532402Y-250886D02*
X534765D01*
X533583Y-252067D02*
Y-249705D01*
X530394Y-245374D02*
X532756D01*
X531575Y-246555D02*
Y-244193D01*
X210236Y-39939D02*
Y-37577D01*
X209055Y-38758D02*
X211417D01*
X215354Y-37799D02*
Y-35437D01*
X214173Y-36618D02*
X216535D01*
X220866Y-35480D02*
Y-33118D01*
X219685Y-34299D02*
X222047D01*
X482677Y-279035D02*
Y-276870D01*
X481595Y-277953D02*
X483760D01*
X483071Y-256594D02*
Y-254429D01*
X481988Y-255512D02*
X484154D01*
X479921Y-279035D02*
Y-276870D01*
X478839Y-277953D02*
X481004D01*
X485827Y-279035D02*
Y-276870D01*
X484744Y-277953D02*
X486909D01*
X476772Y-256594D02*
Y-254429D01*
X475689Y-255512D02*
X477854D01*
X487402Y-256594D02*
Y-254429D01*
X486319Y-255512D02*
X488484D01*
X493012Y-303543D02*
X495177D01*
X494095Y-304626D02*
Y-302461D01*
X485532Y-317717D02*
X487697D01*
X486614Y-318799D02*
Y-316634D01*
X461417Y-311319D02*
Y-309154D01*
X460335Y-310236D02*
X462500D01*
X476772Y-291240D02*
Y-289075D01*
X475689Y-290158D02*
X477854D01*
X483465Y-290846D02*
Y-288681D01*
X482382Y-289764D02*
X484547D01*
X490256Y-310236D02*
X492421D01*
X491339Y-311319D02*
Y-309154D01*
X470965Y-315354D02*
X473130D01*
X472047Y-316437D02*
Y-314272D01*
X466142Y-297539D02*
Y-295374D01*
X465059Y-296457D02*
X467224D01*
X465748Y-311319D02*
Y-309154D01*
X464665Y-310236D02*
X466831D01*
X490256Y-314173D02*
X492421D01*
X491339Y-315256D02*
Y-313090D01*
X488583Y-294783D02*
Y-292618D01*
X487500Y-293701D02*
X489665D01*
X472835Y-291634D02*
Y-289469D01*
X471752Y-290551D02*
X473917D01*
X146850Y14665D02*
Y16831D01*
X145768Y15748D02*
X147933D01*
X164567Y10335D02*
Y12500D01*
X163484Y11417D02*
X165650D01*
X158661Y-12500D02*
Y-10335D01*
X157579Y-11417D02*
X159744D01*
X142520Y13878D02*
Y16043D01*
X141437Y14961D02*
X143602D01*
X141831Y-11811D02*
X143996D01*
X142913Y-12894D02*
Y-10728D01*
X162598Y-12500D02*
Y-10335D01*
X161516Y-11417D02*
X163681D01*
X159843Y10335D02*
Y12500D01*
X158760Y11417D02*
X160925D01*
X151181Y15059D02*
Y17224D01*
X150098Y16142D02*
X152264D01*
X134744Y-6299D02*
X136909D01*
X135827Y-7382D02*
Y-5217D01*
X153543Y-13287D02*
Y-11122D01*
X152461Y-12205D02*
X154626D01*
X169291Y10335D02*
Y12500D01*
X168209Y11417D02*
X170374D01*
X178051Y-87795D02*
X180217D01*
X179134Y-88878D02*
Y-86713D01*
X178445Y-101181D02*
X180610D01*
X179528Y-102264D02*
Y-100098D01*
X198917Y-87795D02*
X201083D01*
X200000Y-88878D02*
Y-86713D01*
X197736Y-102756D02*
X199902D01*
X198819Y-103839D02*
Y-101673D01*
X178051Y-92126D02*
X180217D01*
X179134Y-93209D02*
Y-91043D01*
X198917Y-91732D02*
X201083D01*
X200000Y-92815D02*
Y-90650D01*
X161811Y-55413D02*
Y-53248D01*
X160728Y-54331D02*
X162894D01*
X543307Y-301870D02*
Y-299705D01*
X542224Y-300787D02*
X544390D01*
X161811Y-60138D02*
Y-57973D01*
X160728Y-59055D02*
X162894D01*
X550394Y-301870D02*
Y-299705D01*
X549311Y-300787D02*
X551476D01*
X402461Y-131102D02*
Y-128740D01*
X401279Y-129921D02*
X403642D01*
X416398Y-105824D02*
Y-103462D01*
X415217Y-104643D02*
X417579D01*
X422539Y-105512D02*
X424705D01*
X423622Y-106595D02*
Y-104429D01*
X425787Y-139173D02*
Y-136811D01*
X424606Y-137992D02*
X426968D01*
X51181Y-787D02*
Y1575D01*
X50000Y394D02*
X52362D01*
X57284Y-27362D02*
X59646D01*
X58465Y-28543D02*
Y-26181D01*
X63189Y-6890D02*
Y-4528D01*
X62008Y-5709D02*
X64370D01*
X90075Y-13129D02*
X92240D01*
X91158Y-14212D02*
Y-12047D01*
Y-18110D02*
Y-15748D01*
X89976Y-16929D02*
X92339D01*
X377000Y-155512D02*
X379165D01*
X378083Y-156595D02*
Y-154429D01*
X372000Y-155512D02*
X374165D01*
X373083Y-156595D02*
Y-154429D01*
X43760Y-48355D02*
X45925D01*
X44842Y-49438D02*
Y-47273D01*
X43760Y-43355D02*
X45925D01*
X44842Y-44438D02*
Y-42273D01*
X430367Y-201969D02*
X434107D01*
X432237Y-203839D02*
Y-200098D01*
X425938Y-199213D02*
Y-195276D01*
X423970Y-197244D02*
X427907D01*
X28740Y14469D02*
Y18209D01*
X26870Y16339D02*
X30610D01*
X28740Y7579D02*
Y11319D01*
X26870Y9449D02*
X30610D01*
X28740Y689D02*
Y4429D01*
X26870Y2559D02*
X30610D01*
X28740Y-6201D02*
Y-2461D01*
X26870Y-4331D02*
X30610D01*
X590158Y-227165D02*
Y-225000D01*
X589075Y-226083D02*
X591240D01*
X584350Y-196850D02*
X586516D01*
X585433Y-197933D02*
Y-195768D01*
X583858Y-207776D02*
Y-205610D01*
X582776Y-206693D02*
X584941D01*
X584646Y-231791D02*
Y-229626D01*
X583563Y-230709D02*
X585728D01*
X392224Y-120866D02*
X396161D01*
X394193Y-122835D02*
Y-118898D01*
X80315Y-40157D02*
X84252D01*
X82284Y-42126D02*
Y-38189D01*
X384646Y-218898D02*
Y-216535D01*
X383465Y-217717D02*
X385827D01*
X556299Y-340158D02*
X560236D01*
X558268Y-342126D02*
Y-338189D01*
X531102Y-338976D02*
X535039D01*
X533071Y-340945D02*
Y-337008D01*
X564173Y-319291D02*
X568110D01*
X566142Y-321260D02*
Y-317323D01*
X531496Y-300787D02*
X535433D01*
X533465Y-302756D02*
Y-298819D01*
X123435Y-65403D02*
X127372D01*
X125404Y-67372D02*
Y-63435D01*
X118612Y-47401D02*
X122549D01*
X120581Y-49370D02*
Y-45433D01*
X146850Y-82284D02*
Y-78347D01*
X144882Y-80315D02*
X148819D01*
X161024Y-45669D02*
X164961D01*
X162992Y-47638D02*
Y-43701D01*
X611024Y-253839D02*
Y-251673D01*
X609941Y-252756D02*
X612106D01*
X601634Y-242991D02*
X603799D01*
X602717Y-244074D02*
Y-241909D01*
X601634Y-239054D02*
X603799D01*
X602716Y-240137D02*
Y-237972D01*
X172939Y-123725D02*
Y-121363D01*
X171758Y-122544D02*
X174120D01*
X59016Y-57155D02*
Y-54792D01*
X57835Y-55974D02*
X60197D01*
X609842Y-59842D02*
X612205D01*
X611024Y-61024D02*
Y-58661D01*
X603357Y-82516D02*
Y-80350D01*
X602274Y-81433D02*
X604439D01*
X598425Y-82579D02*
Y-80413D01*
X597342Y-81496D02*
X599508D01*
X156532Y-138287D02*
Y-136122D01*
X155449Y-137205D02*
X157615D01*
X164012Y-137500D02*
Y-135335D01*
X162930Y-136417D02*
X165095D01*
X44193Y-148819D02*
X46358D01*
X45276Y-149902D02*
Y-147736D01*
X220079Y-140157D02*
Y-136221D01*
X218110Y-138189D02*
X222047D01*
X225590Y-134449D02*
Y-130905D01*
X223819Y-132677D02*
X227362D01*
X234055Y-131890D02*
X237598D01*
X235827Y-133661D02*
Y-130118D01*
X193307Y-111811D02*
X197244D01*
X195276Y-113779D02*
Y-109843D01*
X199705Y-130709D02*
X203445D01*
X201575Y-132579D02*
Y-128839D01*
X282776Y-205709D02*
X284941D01*
X283858Y-206791D02*
Y-204626D01*
X284744Y-185433D02*
X286910D01*
X285827Y-186516D02*
Y-184350D01*
X293307Y-195177D02*
Y-193012D01*
X292224Y-194095D02*
X294390D01*
X291339Y-190847D02*
Y-188681D01*
X290256Y-189764D02*
X292421D01*
X228740Y-122835D02*
X232677D01*
X230709Y-124803D02*
Y-120866D01*
X204724Y-122047D02*
X208661D01*
X206693Y-124016D02*
Y-120079D01*
X271260Y-193209D02*
Y-191043D01*
X270177Y-192126D02*
X272342D01*
X278445Y-205906D02*
X280610D01*
X279528Y-206988D02*
Y-204823D01*
X271260Y-197539D02*
Y-195374D01*
X270177Y-196457D02*
X272342D01*
X277264Y-185433D02*
X279429D01*
X278346Y-186516D02*
Y-184350D01*
X188127Y-129331D02*
X190292D01*
X189209Y-130413D02*
Y-128248D01*
Y-120571D02*
Y-118405D01*
X188127Y-119488D02*
X190292D01*
X181827Y-132874D02*
X183993D01*
X182910Y-133957D02*
Y-131791D01*
X181827Y-113583D02*
X183993D01*
X182910Y-114665D02*
Y-112500D01*
X156926Y-117028D02*
X159091D01*
X158008Y-118110D02*
Y-115945D01*
X385083Y-141339D02*
X387445D01*
X386264Y-142520D02*
Y-140157D01*
X163171Y-118679D02*
Y-116514D01*
X162089Y-117597D02*
X164254D01*
X162930Y-129724D02*
X165095D01*
X164012Y-130807D02*
Y-128642D01*
X168441Y-118209D02*
Y-115847D01*
X167260Y-117028D02*
X169623D01*
X158008Y-133268D02*
Y-131102D01*
X156926Y-132185D02*
X159091D01*
X159288Y-126083D02*
Y-123917D01*
X158205Y-125000D02*
X160371D01*
X157811Y-128937D02*
X159977D01*
X158894Y-130020D02*
Y-127854D01*
X18110Y-295669D02*
Y-293307D01*
X16929Y-294488D02*
X19291D01*
X24016Y-294882D02*
X26378D01*
X25197Y-296063D02*
Y-293701D01*
X18008Y-210630D02*
X21945D01*
X19976Y-212598D02*
Y-208661D01*
X8661Y-192520D02*
Y-190157D01*
X7480Y-191339D02*
X9843D01*
X-1181Y-348819D02*
Y-346457D01*
X-2362Y-347638D02*
X0D01*
X19291Y-350000D02*
X21654D01*
X20472Y-351181D02*
Y-348819D01*
X3937Y-234646D02*
X6299D01*
X5118Y-235827D02*
Y-233465D01*
X24016Y-239370D02*
X26378D01*
X25197Y-240551D02*
Y-238189D01*
X23622Y-192520D02*
X25984D01*
X24803Y-193701D02*
Y-191339D01*
X-1575Y-182874D02*
X-394D01*
X-984Y-183465D02*
Y-182185D01*
X-7837Y-174705D02*
X5661D01*
X-7677Y-190945D02*
X5709D01*
X313091Y-243307D02*
X315256D01*
X314173Y-244390D02*
Y-242224D01*
X390945Y-251969D02*
Y-249606D01*
X389764Y-250787D02*
X392126D01*
X386614Y-251969D02*
Y-249606D01*
X385433Y-250787D02*
X387795D01*
X401575Y-251969D02*
Y-249606D01*
X400394Y-250787D02*
X402756D01*
X396850Y-251969D02*
Y-249606D01*
X395669Y-250787D02*
X398031D01*
X406299Y-233071D02*
X408661D01*
X407480Y-234252D02*
Y-231890D01*
X405905Y-238189D02*
X408268D01*
X407087Y-239370D02*
Y-237008D01*
X405118Y-219685D02*
X407480D01*
X406299Y-220866D02*
Y-218504D01*
X405118Y-224016D02*
X407480D01*
X406299Y-225197D02*
Y-222835D01*
X382677Y-249114D02*
Y-246949D01*
X381594Y-248031D02*
X383760D01*
X372047Y-217717D02*
X374410D01*
X373228Y-218898D02*
Y-216535D01*
X371358Y-236614D02*
X373524D01*
X372441Y-237697D02*
Y-235531D01*
X371358Y-241339D02*
X373524D01*
X372441Y-242421D02*
Y-240256D01*
X393799Y-219291D02*
X395965D01*
X394882Y-220374D02*
Y-218209D01*
X612303Y-335276D02*
Y-331339D01*
X610335Y-333307D02*
X614272D01*
X335138Y-235827D02*
X337303D01*
X336221Y-236910D02*
Y-234744D01*
X321358Y-250787D02*
X323524D01*
X322441Y-251870D02*
Y-249705D01*
X321358Y-228740D02*
X323524D01*
X322441Y-229823D02*
Y-227658D01*
X335531Y-242913D02*
X337697D01*
X336614Y-243996D02*
Y-241831D01*
X315846Y-236221D02*
X318012D01*
X316929Y-237303D02*
Y-235138D01*
X-22736Y-192323D02*
X-14469D01*
Y-173622D01*
X-22736D02*
X-14469D01*
X-22736Y-192323D02*
Y-173622D01*
Y-75197D02*
X-14469D01*
Y-56496D01*
X-22736D02*
X-14469D01*
X-22736Y-75197D02*
Y-56496D01*
X338287Y-281102D02*
X340453D01*
X339370Y-282185D02*
Y-280020D01*
X338681Y-303150D02*
X340846D01*
X339764Y-304232D02*
Y-302067D01*
X318996Y-283465D02*
X321161D01*
X320079Y-284547D02*
Y-282382D01*
X318602Y-303543D02*
X320768D01*
X319685Y-304626D02*
Y-302461D01*
X601378Y-238976D02*
X603543D01*
X602461Y-240059D02*
Y-237894D01*
X349508Y-288583D02*
X351673D01*
X350591Y-289665D02*
Y-287500D01*
X333071Y-285335D02*
Y-283169D01*
X331988Y-284252D02*
X334154D01*
X348721Y-296063D02*
X350886D01*
X349803Y-297146D02*
Y-294980D01*
X333071Y-301870D02*
Y-299705D01*
X331988Y-300787D02*
X334154D01*
X327953Y-285335D02*
Y-283169D01*
X326870Y-284252D02*
X329035D01*
X308760Y-289370D02*
X310925D01*
X309842Y-290453D02*
Y-288287D01*
X328740Y-301673D02*
Y-299508D01*
X327658Y-300590D02*
X329823D01*
X307972Y-296457D02*
X310138D01*
X309055Y-297539D02*
Y-295374D01*
X601378Y-242913D02*
X603543D01*
X602461Y-243996D02*
Y-241831D01*
X611122Y-228740D02*
X613287D01*
X612205Y-229823D02*
Y-227658D01*
X621358Y-228346D02*
X623524D01*
X622441Y-229429D02*
Y-227264D01*
X593012Y-52362D02*
X596949D01*
X594980Y-54331D02*
Y-50394D01*
X611811Y-42913D02*
Y-38976D01*
X609842Y-40945D02*
X613779D01*
X599213Y-36220D02*
Y-32283D01*
X597244Y-34252D02*
X601181D01*
X-22736Y-245079D02*
Y-226378D01*
X-14469D01*
Y-245079D02*
Y-226378D01*
X-22736Y-245079D02*
X-14469D01*
X-22736Y-298622D02*
Y-279921D01*
X-14469D01*
Y-298622D02*
Y-279921D01*
X-22736Y-298622D02*
X-14469D01*
X-22736Y-351378D02*
Y-332677D01*
X-14469D01*
Y-351378D02*
Y-332677D01*
X-22736Y-351378D02*
X-14469D01*
X19976Y-264764D02*
Y-260827D01*
X18008Y-262795D02*
X21945D01*
X19976Y-159301D02*
Y-155364D01*
X18008Y-157332D02*
X21945D01*
X19976Y-318898D02*
Y-314961D01*
X18008Y-316929D02*
X21945D01*
X1181Y-339961D02*
Y-336417D01*
X-591Y-338189D02*
X2953D01*
X11417Y-225000D02*
Y-221457D01*
X9646Y-223228D02*
X13189D01*
X10039Y-280709D02*
X13583D01*
X11811Y-282480D02*
Y-278937D01*
X-22736Y-118504D02*
Y-99803D01*
X-14469D01*
Y-118504D02*
Y-99803D01*
X-22736Y-118504D02*
X-14469D01*
X-7677Y-295472D02*
X5709D01*
X-7837Y-279232D02*
X5661D01*
X-984Y-287992D02*
Y-286713D01*
X-1575Y-287402D02*
X-394D01*
X12992Y-177362D02*
Y-173819D01*
X11220Y-175591D02*
X14764D01*
D291*
X42449Y-155940D02*
Y-152791D01*
X48354Y-155940D02*
Y-152791D01*
X42449Y-155940D02*
X48354D01*
X42449Y-152791D02*
X48354D01*
X440158Y-156102D02*
Y-152559D01*
X447244Y-156102D02*
Y-152559D01*
X440158Y-156102D02*
X447244D01*
X440158Y-152559D02*
X447244D01*
X435531Y-142520D02*
X439074D01*
X435531Y-149606D02*
X439074D01*
X435531D02*
Y-142520D01*
X439074Y-149606D02*
Y-142520D01*
X439961Y-142520D02*
X443504D01*
X439961Y-149606D02*
X443504D01*
X439961D02*
Y-142520D01*
X443504Y-149606D02*
Y-142520D01*
X451083D02*
X454626D01*
X451083Y-149606D02*
X454626D01*
X451083D02*
Y-142520D01*
X454626Y-149606D02*
Y-142520D01*
X73622Y-984D02*
Y2559D01*
X66535Y-984D02*
Y2559D01*
X73622D01*
X66535Y-984D02*
X73622D01*
X51378Y-7480D02*
Y-3937D01*
X58465Y-7480D02*
Y-3937D01*
X51378Y-7480D02*
X58465D01*
X51378Y-3937D02*
X58465D01*
X562605Y-284652D02*
Y-274416D01*
X572960D01*
Y-284652D02*
Y-274416D01*
X562605Y-284652D02*
X572960D01*
X530101Y-284646D02*
X538369D01*
X530101Y-280315D02*
X538369D01*
X530101Y-284646D02*
Y-280315D01*
X538369Y-284646D02*
Y-280315D01*
X539055Y-279803D02*
Y-269567D01*
X528701Y-279803D02*
X539055D01*
X528701D02*
Y-269567D01*
X539055D01*
X562861Y-270676D02*
X571129D01*
X562861Y-275007D02*
X571129D01*
Y-270676D01*
X562861Y-275007D02*
Y-270676D01*
X539961Y-284055D02*
Y-275787D01*
X544291Y-284055D02*
Y-275787D01*
X539961D02*
X544291D01*
X539961Y-284055D02*
X544291D01*
X552625Y-273432D02*
X560893D01*
X552625Y-277763D02*
X560893D01*
Y-273432D01*
X552625Y-277763D02*
Y-273432D01*
X107677Y-31890D02*
X113583D01*
X107677Y-28740D02*
X113583D01*
X107677Y-31890D02*
Y-28740D01*
X113583Y-31890D02*
Y-28740D01*
X108858Y-19488D02*
X113189D01*
X108858Y-27756D02*
X113189D01*
X108858D02*
Y-19488D01*
X113189Y-27756D02*
Y-19488D01*
X72875Y-135915D02*
X97088D01*
X72875Y-111703D02*
X97088D01*
Y-135915D02*
Y-111703D01*
X72875Y-135915D02*
Y-111703D01*
X55454Y-136604D02*
Y-130699D01*
X67265Y-136604D02*
Y-130699D01*
X55454D02*
X67265D01*
X55454Y-136604D02*
X67265D01*
X46399Y-113967D02*
X52304D01*
X46399Y-117116D02*
X52304D01*
X46399D02*
Y-113967D01*
X52304Y-117116D02*
Y-113967D01*
X68052Y-130502D02*
Y-117116D01*
X59785Y-130502D02*
Y-117116D01*
X68052D01*
X59785Y-130502D02*
X68052D01*
X46399Y-113179D02*
X52304D01*
X46399Y-110029D02*
X52304D01*
Y-113179D02*
Y-110029D01*
X46399Y-113179D02*
Y-110029D01*
Y-109636D02*
X52304D01*
X46399Y-106486D02*
X52304D01*
Y-109636D02*
Y-106486D01*
X46399Y-109636D02*
Y-106486D01*
X124586Y-120281D02*
Y-112013D01*
X137971Y-120281D02*
Y-112013D01*
X124586D02*
X137971D01*
X124586Y-120281D02*
X137971D01*
X124522Y-114596D02*
Y-106328D01*
X137908Y-114596D02*
Y-106328D01*
X124522D02*
X137908D01*
X124522Y-114596D02*
X137908D01*
X292146Y-162146D02*
Y-108878D01*
Y-162146D02*
X303917D01*
Y-108878D01*
X292146D02*
X303917D01*
X315177Y-162047D02*
X327343D01*
Y-119291D01*
X315177D02*
X327343D01*
X315177Y-162047D02*
Y-119291D01*
X319291Y-140669D02*
X323228D01*
X321260Y-142638D02*
Y-138701D01*
X248948Y-111128D02*
X257215D01*
X248948Y-124514D02*
X257215D01*
Y-111128D01*
X248948Y-124514D02*
Y-111128D01*
X259646Y-134646D02*
Y-123228D01*
X280906Y-134646D02*
Y-123228D01*
X259646D02*
X280906D01*
X259646Y-134646D02*
X280906D01*
X259646Y-146850D02*
X280906D01*
X259646Y-135433D02*
X280906D01*
Y-146850D02*
Y-135433D01*
X259646Y-146850D02*
Y-135433D01*
Y-158268D02*
X280906D01*
X259646Y-146850D02*
X280906D01*
Y-158268D02*
Y-146850D01*
X259646Y-158268D02*
Y-146850D01*
X162241Y-123031D02*
Y-119882D01*
X156335Y-123031D02*
Y-119882D01*
X162241D01*
X156335Y-123031D02*
X162241D01*
X377559Y-225197D02*
X395669D01*
Y-243307D02*
Y-225197D01*
X377559Y-243307D02*
X395669D01*
X377559D02*
Y-225197D01*
X605413Y-299213D02*
Y-260827D01*
Y-299213D02*
X631299D01*
Y-260827D01*
X605413D02*
X631299D01*
X132480Y-8268D02*
X138386D01*
X132480Y-11417D02*
X138386D01*
X132480D02*
Y-8268D01*
X138386Y-11417D02*
Y-8268D01*
X580905Y-212598D02*
X586811D01*
X580905Y-215748D02*
X586811D01*
Y-212598D01*
X580905Y-215748D02*
Y-212598D01*
X583661Y-245374D02*
Y-238287D01*
X580118Y-245374D02*
Y-238287D01*
Y-245374D02*
X583661D01*
X580118Y-238287D02*
X583661D01*
X592520Y-187598D02*
Y-184055D01*
X585433Y-187598D02*
Y-184055D01*
X592520D01*
X585433Y-187598D02*
X592520D01*
X588189Y-180118D02*
X591339D01*
X588189Y-174213D02*
X591339D01*
Y-180118D02*
Y-174213D01*
X588189Y-180118D02*
Y-174213D01*
X588156Y-157269D02*
X591305D01*
X588156Y-163174D02*
X591305D01*
X588156D02*
Y-157269D01*
X591305Y-163174D02*
Y-157269D01*
X585339Y-155602D02*
X629622D01*
X585339Y-182193D02*
X629622D01*
Y-155602D01*
X585339Y-182193D02*
Y-155602D01*
X600787Y-146260D02*
Y-142717D01*
X593701Y-146260D02*
Y-142717D01*
Y-146260D02*
X600787D01*
X593701Y-142717D02*
X600787D01*
X538304Y-257776D02*
Y-254232D01*
X531217Y-257776D02*
Y-254232D01*
X538304D01*
X531217Y-257776D02*
X538304D01*
X537127Y-252658D02*
Y-249114D01*
X530040Y-252658D02*
Y-249114D01*
X537127D01*
X530040Y-252658D02*
X537127D01*
X535119Y-247146D02*
Y-243602D01*
X528032Y-247146D02*
Y-243602D01*
X535119D01*
X528032Y-247146D02*
X535119D01*
X208465Y-42301D02*
X212008D01*
X208465Y-35215D02*
X212008D01*
Y-42301D02*
Y-35215D01*
X208465Y-42301D02*
Y-35215D01*
X213583Y-40161D02*
X217126D01*
X213583Y-33075D02*
X217126D01*
Y-40161D02*
Y-33075D01*
X213583Y-40161D02*
Y-33075D01*
X219094Y-37842D02*
X222638D01*
X219094Y-30756D02*
X222638D01*
Y-37842D02*
Y-30756D01*
X219094Y-37842D02*
Y-30756D01*
X481102Y-275000D02*
X484252D01*
X481102Y-280906D02*
X484252D01*
Y-275000D01*
X481102Y-280906D02*
Y-275000D01*
X481496Y-258465D02*
X484646D01*
X481496Y-252559D02*
X484646D01*
X481496Y-258465D02*
Y-252559D01*
X484646Y-258465D02*
Y-252559D01*
X478346Y-280906D02*
X481496D01*
X478346Y-275000D02*
X481496D01*
X478346Y-280906D02*
Y-275000D01*
X481496Y-280906D02*
Y-275000D01*
X484252Y-280906D02*
X487402D01*
X484252Y-275000D02*
X487402D01*
X484252Y-280906D02*
Y-275000D01*
X487402Y-280906D02*
Y-275000D01*
X475197Y-252559D02*
X478346D01*
X475197Y-258465D02*
X478346D01*
Y-252559D01*
X475197Y-258465D02*
Y-252559D01*
X485827D02*
X488976D01*
X485827Y-258465D02*
X488976D01*
Y-252559D01*
X485827Y-258465D02*
Y-252559D01*
X490551Y-305315D02*
Y-301772D01*
X497638Y-305315D02*
Y-301772D01*
X490551D02*
X497638D01*
X490551Y-305315D02*
X497638D01*
X483071Y-319488D02*
Y-315945D01*
X490158Y-319488D02*
Y-315945D01*
X483071D02*
X490158D01*
X483071Y-319488D02*
X490158D01*
X459646Y-306693D02*
X463189D01*
X459646Y-313779D02*
X463189D01*
Y-306693D01*
X459646Y-313779D02*
Y-306693D01*
X475000Y-293701D02*
X478543D01*
X475000Y-286614D02*
X478543D01*
X475000Y-293701D02*
Y-286614D01*
X478543Y-293701D02*
Y-286614D01*
X481693Y-293307D02*
X485236D01*
X481693Y-286221D02*
X485236D01*
X481693Y-293307D02*
Y-286221D01*
X485236Y-293307D02*
Y-286221D01*
X487795Y-312008D02*
Y-308465D01*
X494882Y-312008D02*
Y-308465D01*
X487795D02*
X494882D01*
X487795Y-312008D02*
X494882D01*
X475591Y-317126D02*
Y-313583D01*
X468504Y-317126D02*
Y-313583D01*
Y-317126D02*
X475591D01*
X468504Y-313583D02*
X475591D01*
X464370Y-300000D02*
X467913D01*
X464370Y-292913D02*
X467913D01*
X464370Y-300000D02*
Y-292913D01*
X467913Y-300000D02*
Y-292913D01*
X464173Y-307283D02*
X467323D01*
X464173Y-313189D02*
X467323D01*
Y-307283D01*
X464173Y-313189D02*
Y-307283D01*
X488386Y-315748D02*
Y-312598D01*
X494291Y-315748D02*
Y-312598D01*
X488386D02*
X494291D01*
X488386Y-315748D02*
X494291D01*
X487008Y-296654D02*
X490158D01*
X487008Y-290748D02*
X490158D01*
X487008Y-296654D02*
Y-290748D01*
X490158Y-296654D02*
Y-290748D01*
X471260Y-293504D02*
X474409D01*
X471260Y-287598D02*
X474409D01*
X471260Y-293504D02*
Y-287598D01*
X474409Y-293504D02*
Y-287598D01*
X145276Y12795D02*
X148425D01*
X145276Y18701D02*
X148425D01*
X145276Y12795D02*
Y18701D01*
X148425Y12795D02*
Y18701D01*
X162992Y8465D02*
X166142D01*
X162992Y14370D02*
X166142D01*
X162992Y8465D02*
Y14370D01*
X166142Y8465D02*
Y14370D01*
X157087Y-8465D02*
X160236D01*
X157087Y-14370D02*
X160236D01*
Y-8465D01*
X157087Y-14370D02*
Y-8465D01*
X140748Y11417D02*
X144291D01*
X140748Y18504D02*
X144291D01*
X140748Y11417D02*
Y18504D01*
X144291Y11417D02*
Y18504D01*
X146457Y-13583D02*
Y-10039D01*
X139370Y-13583D02*
Y-10039D01*
Y-13583D02*
X146457D01*
X139370Y-10039D02*
X146457D01*
X160827Y-7874D02*
X164370D01*
X160827Y-14961D02*
X164370D01*
Y-7874D01*
X160827Y-14961D02*
Y-7874D01*
X158071Y7874D02*
X161614D01*
X158071Y14961D02*
X161614D01*
X158071Y7874D02*
Y14961D01*
X161614Y7874D02*
Y14961D01*
X149409Y12598D02*
X152953D01*
X149409Y19685D02*
X152953D01*
X149409Y12598D02*
Y19685D01*
X152953Y12598D02*
Y19685D01*
X139370Y-8071D02*
Y-4528D01*
X132283Y-8071D02*
Y-4528D01*
Y-8071D02*
X139370D01*
X132283Y-4528D02*
X139370D01*
X151772Y-8661D02*
X155315D01*
X151772Y-15748D02*
X155315D01*
Y-8661D01*
X151772Y-15748D02*
Y-8661D01*
X167520Y7874D02*
X171063D01*
X167520Y14961D02*
X171063D01*
X167520Y7874D02*
Y14961D01*
X171063Y7874D02*
Y14961D01*
X176181Y-89370D02*
Y-86221D01*
X182087Y-89370D02*
Y-86221D01*
X176181D02*
X182087D01*
X176181Y-89370D02*
X182087D01*
X176575Y-102756D02*
Y-99606D01*
X182480Y-102756D02*
Y-99606D01*
X176575D02*
X182480D01*
X176575Y-102756D02*
X182480D01*
X202953Y-89370D02*
Y-86221D01*
X197047Y-89370D02*
Y-86221D01*
Y-89370D02*
X202953D01*
X197047Y-86221D02*
X202953D01*
X201772Y-104331D02*
Y-101181D01*
X195866Y-104331D02*
Y-101181D01*
Y-104331D02*
X201772D01*
X195866Y-101181D02*
X201772D01*
X182087Y-93701D02*
Y-90551D01*
X176181Y-93701D02*
Y-90551D01*
Y-93701D02*
X182087D01*
X176181Y-90551D02*
X182087D01*
X197047Y-93307D02*
Y-90158D01*
X202953Y-93307D02*
Y-90158D01*
X197047D02*
X202953D01*
X197047Y-93307D02*
X202953D01*
X158858Y-52756D02*
X164764D01*
X158858Y-55905D02*
X164764D01*
X158858D02*
Y-52756D01*
X164764Y-55905D02*
Y-52756D01*
X540354Y-302362D02*
X546260D01*
X540354Y-299213D02*
X546260D01*
Y-302362D02*
Y-299213D01*
X540354Y-302362D02*
Y-299213D01*
X158858Y-57480D02*
X164764D01*
X158858Y-60630D02*
X164764D01*
X158858D02*
Y-57480D01*
X164764Y-60630D02*
Y-57480D01*
X547441Y-299213D02*
X553346D01*
X547441Y-302362D02*
X553346D01*
X547441D02*
Y-299213D01*
X553346Y-302362D02*
Y-299213D01*
X399508Y-131496D02*
X405413D01*
X399508Y-128347D02*
X405413D01*
X399508Y-131496D02*
Y-128347D01*
X405413Y-131496D02*
Y-128347D01*
X412855Y-106415D02*
X419941D01*
X412855Y-102872D02*
X419941D01*
X412855Y-106415D02*
Y-102872D01*
X419941Y-106415D02*
Y-102872D01*
X426575Y-107087D02*
Y-103937D01*
X420669Y-107087D02*
Y-103937D01*
X426575D01*
X420669Y-107087D02*
X426575D01*
X421654Y-140157D02*
X429921D01*
X421654Y-135827D02*
X429921D01*
X421654Y-140157D02*
Y-135827D01*
X429921Y-140157D02*
Y-135827D01*
X47638Y2165D02*
X54724D01*
X47638Y-1378D02*
X54724D01*
Y2165D01*
X47638Y-1378D02*
Y2165D01*
X54331Y-29528D02*
Y-25197D01*
X62598Y-29528D02*
Y-25197D01*
X54331Y-29528D02*
X62598D01*
X54331Y-25197D02*
X62598D01*
X59646Y-3937D02*
X66732D01*
X59646Y-7480D02*
X66732D01*
Y-3937D01*
X59646Y-7480D02*
Y-3937D01*
X94110Y-14704D02*
Y-11555D01*
X88205Y-14704D02*
Y-11555D01*
X94110D01*
X88205Y-14704D02*
X94110D01*
X87614Y-15157D02*
X94701D01*
X87614Y-18701D02*
X94701D01*
Y-15157D01*
X87614Y-18701D02*
Y-15157D01*
X376508Y-158465D02*
Y-152559D01*
X379657Y-158465D02*
Y-152559D01*
X376508D02*
X379657D01*
X376508Y-158465D02*
X379657D01*
X371508D02*
Y-152559D01*
X374657Y-158465D02*
Y-152559D01*
X371508D02*
X374657D01*
X371508Y-158465D02*
X374657D01*
X41890Y-49930D02*
Y-46781D01*
X47795Y-49930D02*
Y-46781D01*
X41890Y-49930D02*
X47795D01*
X41890Y-46781D02*
X47795D01*
X41890Y-44930D02*
Y-41781D01*
X47795Y-44930D02*
Y-41781D01*
X41890Y-44930D02*
X47795D01*
X41890Y-41781D02*
X47795D01*
X429875Y-206102D02*
Y-197835D01*
X434599Y-206102D02*
Y-197835D01*
X429875D02*
X434599D01*
X429875Y-206102D02*
X434599D01*
X421804Y-190551D02*
X430072D01*
X421804Y-203937D02*
X430072D01*
X421804D02*
Y-190551D01*
X430072Y-203937D02*
Y-190551D01*
X23425Y13386D02*
X34055D01*
X23425Y19291D02*
X34055D01*
X23425Y13386D02*
Y19291D01*
X34055Y13386D02*
Y19291D01*
X23425Y6496D02*
X34055D01*
X23425Y12402D02*
X34055D01*
X23425Y6496D02*
Y12402D01*
X34055Y6496D02*
Y12402D01*
X23425Y-394D02*
X34055D01*
X23425Y5512D02*
X34055D01*
X23425Y-394D02*
Y5512D01*
X34055Y-394D02*
Y5512D01*
X23425Y-7283D02*
X34055D01*
X23425Y-1378D02*
X34055D01*
X23425Y-7283D02*
Y-1378D01*
X34055Y-7283D02*
Y-1378D01*
X588386Y-222539D02*
X591929D01*
X588386Y-229626D02*
X591929D01*
X588386D02*
Y-222539D01*
X591929Y-229626D02*
Y-222539D01*
X582480Y-198425D02*
Y-195276D01*
X588386Y-198425D02*
Y-195276D01*
X582480Y-198425D02*
X588386D01*
X582480Y-195276D02*
X588386D01*
X580905Y-205118D02*
X586811D01*
X580905Y-208268D02*
X586811D01*
Y-205118D01*
X580905Y-208268D02*
Y-205118D01*
X582874Y-227165D02*
X586417D01*
X582874Y-234252D02*
X586417D01*
X582874D02*
Y-227165D01*
X586417Y-234252D02*
Y-227165D01*
X403445Y-125591D02*
Y-116142D01*
X384941Y-125591D02*
Y-116142D01*
Y-125591D02*
X403445D01*
X384941Y-116142D02*
X403445D01*
X73032Y-44882D02*
Y-35433D01*
X91535Y-44882D02*
Y-35433D01*
X73032D02*
X91535D01*
X73032Y-44882D02*
X91535D01*
X381102Y-219488D02*
X388189D01*
X381102Y-215945D02*
X388189D01*
Y-219488D02*
Y-215945D01*
X381102Y-219488D02*
Y-215945D01*
X551575Y-344291D02*
Y-336024D01*
X564961Y-344291D02*
Y-336024D01*
X551575Y-344291D02*
X564961D01*
X551575Y-336024D02*
X564961D01*
X539764Y-343110D02*
Y-334842D01*
X526378Y-343110D02*
Y-334842D01*
X539764D01*
X526378Y-343110D02*
X539764D01*
X572835Y-323425D02*
Y-315158D01*
X559449Y-323425D02*
Y-315158D01*
X572835D01*
X559449Y-323425D02*
X572835D01*
X540158Y-304921D02*
Y-296654D01*
X526772Y-304921D02*
Y-296654D01*
X540158D01*
X526772Y-304921D02*
X540158D01*
X132097Y-69537D02*
Y-61269D01*
X118711Y-69537D02*
Y-61269D01*
X132097D01*
X118711Y-69537D02*
X132097D01*
X113888Y-51535D02*
Y-43267D01*
X127274Y-51535D02*
Y-43267D01*
X113888Y-51535D02*
X127274D01*
X113888Y-43267D02*
X127274D01*
X140157Y-76181D02*
X153543D01*
X140157Y-84449D02*
X153543D01*
Y-76181D01*
X140157Y-84449D02*
Y-76181D01*
X158858Y-52362D02*
Y-38976D01*
X167126Y-52362D02*
Y-38976D01*
X158858D02*
X167126D01*
X158858Y-52362D02*
X167126D01*
X608071Y-251181D02*
X613976D01*
X608071Y-254331D02*
X613976D01*
X608071D02*
Y-251181D01*
X613976Y-254331D02*
Y-251181D01*
X605866Y-244566D02*
Y-241417D01*
X599567Y-244566D02*
Y-241417D01*
X605866D01*
X599567Y-244566D02*
X605866D01*
X605866Y-240629D02*
Y-237480D01*
X599567Y-240629D02*
Y-237480D01*
X605866D01*
X599567Y-240629D02*
X605866D01*
X170971Y-126284D02*
X174908D01*
X170971Y-118804D02*
X174908D01*
Y-126284D02*
Y-118804D01*
X170971Y-126284D02*
Y-118804D01*
X57047Y-52233D02*
X60984D01*
X57047Y-59714D02*
X60984D01*
X57047D02*
Y-52233D01*
X60984Y-59714D02*
Y-52233D01*
X607283Y-61811D02*
Y-57874D01*
X614764Y-61811D02*
Y-57874D01*
X607283Y-61811D02*
X614764D01*
X607283Y-57874D02*
X614764D01*
X601782Y-84386D02*
X604931D01*
X601782Y-78480D02*
X604931D01*
Y-84386D02*
Y-78480D01*
X601782Y-84386D02*
Y-78480D01*
X596850Y-84449D02*
X600000D01*
X596850Y-78543D02*
X600000D01*
Y-84449D02*
Y-78543D01*
X596850Y-84449D02*
Y-78543D01*
X153579Y-135630D02*
X159485D01*
X153579Y-138779D02*
X159485D01*
Y-135630D01*
X153579Y-138779D02*
Y-135630D01*
X161059Y-134843D02*
X166965D01*
X161059Y-137992D02*
X166965D01*
Y-134843D01*
X161059Y-137992D02*
Y-134843D01*
X42323Y-150394D02*
Y-147244D01*
X48228Y-150394D02*
Y-147244D01*
X42323Y-150394D02*
X48228D01*
X42323Y-147244D02*
X48228D01*
X213386Y-134055D02*
X226772D01*
X213386Y-142323D02*
X226772D01*
Y-134055D01*
X213386Y-142323D02*
Y-134055D01*
X221457Y-130512D02*
X229724D01*
X221457Y-134843D02*
X229724D01*
Y-130512D01*
X221457Y-134843D02*
Y-130512D01*
X239961Y-134055D02*
Y-129724D01*
X231693Y-134055D02*
Y-129724D01*
X239961D01*
X231693Y-134055D02*
X239961D01*
X201969Y-115945D02*
Y-107677D01*
X188583Y-115945D02*
Y-107677D01*
X201969D01*
X188583Y-115945D02*
X201969D01*
X196457Y-133661D02*
Y-127756D01*
X206693Y-133661D02*
Y-127756D01*
X196457Y-133661D02*
X206693D01*
X196457Y-127756D02*
X206693D01*
X285433Y-208661D02*
Y-202756D01*
X282283Y-208661D02*
Y-202756D01*
X285433D01*
X282283Y-208661D02*
X285433D01*
X284252Y-188386D02*
Y-182480D01*
X287402Y-188386D02*
Y-182480D01*
X284252Y-188386D02*
X287402D01*
X284252Y-182480D02*
X287402D01*
X290354Y-195669D02*
X296260D01*
X290354Y-192520D02*
X296260D01*
Y-195669D02*
Y-192520D01*
X290354Y-195669D02*
Y-192520D01*
X288386Y-191339D02*
X294291D01*
X288386Y-188189D02*
X294291D01*
Y-191339D02*
Y-188189D01*
X288386Y-191339D02*
Y-188189D01*
X241535Y-137598D02*
Y-108071D01*
X219882Y-137598D02*
Y-108071D01*
X241535D01*
X219882Y-137598D02*
X241535D01*
X216929Y-135433D02*
Y-108661D01*
X196457Y-135433D02*
Y-108661D01*
X216929D01*
X196457Y-135433D02*
X216929D01*
X268307Y-190551D02*
X274213D01*
X268307Y-193701D02*
X274213D01*
X268307D02*
Y-190551D01*
X274213Y-193701D02*
Y-190551D01*
X281102Y-208858D02*
Y-202953D01*
X277953Y-208858D02*
Y-202953D01*
X281102D01*
X277953Y-208858D02*
X281102D01*
X268307Y-194882D02*
X274213D01*
X268307Y-198031D02*
X274213D01*
X268307D02*
Y-194882D01*
X274213Y-198031D02*
Y-194882D01*
X276772Y-188386D02*
Y-182480D01*
X279921Y-188386D02*
Y-182480D01*
X276772Y-188386D02*
X279921D01*
X276772Y-182480D02*
X279921D01*
X191571Y-133661D02*
Y-125000D01*
X186847Y-133661D02*
Y-125000D01*
X191571D01*
X186847Y-133661D02*
X191571D01*
X186847Y-115157D02*
X191571D01*
X186847Y-123819D02*
X191571D01*
Y-115157D01*
X186847Y-123819D02*
Y-115157D01*
X179957Y-134449D02*
Y-131299D01*
X185863Y-134449D02*
Y-131299D01*
X179957D02*
X185863D01*
X179957Y-134449D02*
X185863D01*
X179957Y-115157D02*
Y-112008D01*
X185863Y-115157D02*
Y-112008D01*
X179957D02*
X185863D01*
X179957Y-115157D02*
X185863D01*
X159583Y-119980D02*
Y-114075D01*
X156434Y-119980D02*
Y-114075D01*
Y-119980D02*
X159583D01*
X156434Y-114075D02*
X159583D01*
X382524Y-143307D02*
Y-139370D01*
X390004Y-143307D02*
Y-139370D01*
X382524Y-143307D02*
X390004D01*
X382524Y-139370D02*
X390004D01*
X160218Y-119171D02*
X166124D01*
X160218Y-116022D02*
X166124D01*
X160218Y-119171D02*
Y-116022D01*
X166124Y-119171D02*
Y-116022D01*
X165587Y-132677D02*
Y-126772D01*
X162437Y-132677D02*
Y-126772D01*
Y-132677D02*
X165587D01*
X162437Y-126772D02*
X165587D01*
X166473Y-113287D02*
X170410D01*
X166473Y-120768D02*
X170410D01*
X166473D02*
Y-113287D01*
X170410Y-120768D02*
Y-113287D01*
X155056Y-133760D02*
X160961D01*
X155056Y-130610D02*
X160961D01*
X155056Y-133760D02*
Y-130610D01*
X160961Y-133760D02*
Y-130610D01*
X156335Y-123425D02*
X162241D01*
X156335Y-126575D02*
X162241D01*
Y-123425D01*
X156335Y-126575D02*
Y-123425D01*
X161847Y-130512D02*
Y-127362D01*
X155941Y-130512D02*
Y-127362D01*
X161847D01*
X155941Y-130512D02*
X161847D01*
X16339Y-298031D02*
X19882D01*
X16339Y-290945D02*
X19882D01*
Y-298031D02*
Y-290945D01*
X16339Y-298031D02*
Y-290945D01*
X21654Y-296654D02*
Y-293110D01*
X28740Y-296654D02*
Y-293110D01*
X21654Y-296654D02*
X28740D01*
X21654Y-293110D02*
X28740D01*
X26473Y-218898D02*
Y-202362D01*
X11512Y-218898D02*
X26473D01*
X11512Y-202362D02*
X26473D01*
X11512Y-218898D02*
Y-202362D01*
X6890Y-194882D02*
X10433D01*
X6890Y-187795D02*
X10433D01*
Y-194882D02*
Y-187795D01*
X6890Y-194882D02*
Y-187795D01*
X-2953Y-351181D02*
X591D01*
X-2953Y-344094D02*
X591D01*
X-2953Y-351181D02*
Y-344094D01*
X591Y-351181D02*
Y-344094D01*
X16929Y-351772D02*
Y-348228D01*
X24016Y-351772D02*
Y-348228D01*
X16929D02*
X24016D01*
X16929Y-351772D02*
X24016D01*
X1575Y-236417D02*
Y-232874D01*
X8661Y-236417D02*
Y-232874D01*
X1575D02*
X8661D01*
X1575Y-236417D02*
X8661D01*
X21654Y-241142D02*
Y-237598D01*
X28740Y-241142D02*
Y-237598D01*
X21654D02*
X28740D01*
X21654Y-241142D02*
X28740D01*
X21260Y-194291D02*
Y-190748D01*
X28346Y-194291D02*
Y-190748D01*
X21260D02*
X28346D01*
X21260Y-194291D02*
X28346D01*
X310630Y-245079D02*
Y-241535D01*
X317717Y-245079D02*
Y-241535D01*
X310630D02*
X317717D01*
X310630Y-245079D02*
X317717D01*
X389173Y-247244D02*
X392717D01*
X389173Y-254331D02*
X392717D01*
Y-247244D01*
X389173Y-254331D02*
Y-247244D01*
X384842D02*
X388386D01*
X384842Y-254331D02*
X388386D01*
Y-247244D01*
X384842Y-254331D02*
Y-247244D01*
X399803D02*
X403346D01*
X399803Y-254331D02*
X403346D01*
Y-247244D01*
X399803Y-254331D02*
Y-247244D01*
X395079D02*
X398622D01*
X395079Y-254331D02*
X398622D01*
Y-247244D01*
X395079Y-254331D02*
Y-247244D01*
X403937Y-234842D02*
Y-231299D01*
X411024Y-234842D02*
Y-231299D01*
X403937D02*
X411024D01*
X403937Y-234842D02*
X411024D01*
X403543Y-239961D02*
Y-236417D01*
X410630Y-239961D02*
Y-236417D01*
X403543D02*
X410630D01*
X403543Y-239961D02*
X410630D01*
X402756Y-221457D02*
Y-217913D01*
X409842Y-221457D02*
Y-217913D01*
X402756D02*
X409842D01*
X402756Y-221457D02*
X409842D01*
X402756Y-225787D02*
Y-222244D01*
X409842Y-225787D02*
Y-222244D01*
X402756D02*
X409842D01*
X402756Y-225787D02*
X409842D01*
X380906Y-251575D02*
X384449D01*
X380906Y-244488D02*
X384449D01*
X380906Y-251575D02*
Y-244488D01*
X384449Y-251575D02*
Y-244488D01*
X376772Y-219488D02*
Y-215945D01*
X369685Y-219488D02*
Y-215945D01*
Y-219488D02*
X376772D01*
X369685Y-215945D02*
X376772D01*
X368898Y-238386D02*
Y-234842D01*
X375984Y-238386D02*
Y-234842D01*
X368898D02*
X375984D01*
X368898Y-238386D02*
X375984D01*
X368898Y-243110D02*
Y-239567D01*
X375984Y-243110D02*
Y-239567D01*
X368898D02*
X375984D01*
X368898Y-243110D02*
X375984D01*
X398425Y-221063D02*
Y-217520D01*
X391339Y-221063D02*
Y-217520D01*
Y-221063D02*
X398425D01*
X391339Y-217520D02*
X398425D01*
X594823Y-359193D02*
Y-307421D01*
Y-359193D02*
X629783D01*
X594823Y-307421D02*
X629783D01*
Y-359193D02*
Y-307421D01*
X339764Y-237598D02*
Y-234055D01*
X332677Y-237598D02*
Y-234055D01*
Y-237598D02*
X339764D01*
X332677Y-234055D02*
X339764D01*
X318898Y-252559D02*
Y-249016D01*
X325984Y-252559D02*
Y-249016D01*
X318898D02*
X325984D01*
X318898Y-252559D02*
X325984D01*
X318898Y-230512D02*
Y-226969D01*
X325984Y-230512D02*
Y-226969D01*
X318898D02*
X325984D01*
X318898Y-230512D02*
X325984D01*
X340158Y-244685D02*
Y-241142D01*
X333071Y-244685D02*
Y-241142D01*
Y-244685D02*
X340158D01*
X333071Y-241142D02*
X340158D01*
X313386Y-237992D02*
Y-234449D01*
X320472Y-237992D02*
Y-234449D01*
X313386D02*
X320472D01*
X313386Y-237992D02*
X320472D01*
X335827Y-282874D02*
Y-279331D01*
X342913Y-282874D02*
Y-279331D01*
X335827D02*
X342913D01*
X335827Y-282874D02*
X342913D01*
X336221Y-304921D02*
Y-301378D01*
X343307Y-304921D02*
Y-301378D01*
X336221D02*
X343307D01*
X336221Y-304921D02*
X343307D01*
X316535Y-285236D02*
Y-281693D01*
X323622Y-285236D02*
Y-281693D01*
X316535D02*
X323622D01*
X316535Y-285236D02*
X323622D01*
X316142Y-305315D02*
Y-301772D01*
X323228Y-305315D02*
Y-301772D01*
X316142D02*
X323228D01*
X316142Y-305315D02*
X323228D01*
X598917Y-240748D02*
Y-237205D01*
X606004Y-240748D02*
Y-237205D01*
X598917D02*
X606004D01*
X598917Y-240748D02*
X606004D01*
X354134Y-290354D02*
Y-286811D01*
X347047Y-290354D02*
Y-286811D01*
Y-290354D02*
X354134D01*
X347047Y-286811D02*
X354134D01*
X331299Y-280709D02*
X334842D01*
X331299Y-287795D02*
X334842D01*
Y-280709D01*
X331299Y-287795D02*
Y-280709D01*
X353346Y-297835D02*
Y-294291D01*
X346260Y-297835D02*
Y-294291D01*
Y-297835D02*
X353346D01*
X346260Y-294291D02*
X353346D01*
X331299Y-304331D02*
X334842D01*
X331299Y-297244D02*
X334842D01*
X331299Y-304331D02*
Y-297244D01*
X334842Y-304331D02*
Y-297244D01*
X326181Y-280709D02*
X329724D01*
X326181Y-287795D02*
X329724D01*
Y-280709D01*
X326181Y-287795D02*
Y-280709D01*
X306299Y-291142D02*
Y-287598D01*
X313386Y-291142D02*
Y-287598D01*
X306299D02*
X313386D01*
X306299Y-291142D02*
X313386D01*
X326969Y-304134D02*
X330512D01*
X326969Y-297047D02*
X330512D01*
X326969Y-304134D02*
Y-297047D01*
X330512Y-304134D02*
Y-297047D01*
X305512Y-298228D02*
Y-294685D01*
X312598Y-298228D02*
Y-294685D01*
X305512D02*
X312598D01*
X305512Y-298228D02*
X312598D01*
X598917Y-244685D02*
Y-241142D01*
X606004Y-244685D02*
Y-241142D01*
X598917D02*
X606004D01*
X598917Y-244685D02*
X606004D01*
X615748Y-230512D02*
Y-226969D01*
X608661Y-230512D02*
Y-226969D01*
Y-230512D02*
X615748D01*
X608661Y-226969D02*
X615748D01*
X618898Y-230118D02*
Y-226575D01*
X625984Y-230118D02*
Y-226575D01*
X618898D02*
X625984D01*
X618898Y-230118D02*
X625984D01*
X585728Y-57087D02*
Y-47638D01*
X604232Y-57087D02*
Y-47638D01*
X585728D02*
X604232D01*
X585728Y-57087D02*
X604232D01*
X607677Y-34252D02*
X615945D01*
X607677Y-47638D02*
X615945D01*
Y-34252D01*
X607677Y-47638D02*
Y-34252D01*
X593504Y-23622D02*
X604921D01*
X593504Y-44882D02*
X604921D01*
Y-23622D01*
X593504Y-44882D02*
Y-23622D01*
X-54527Y-331505D02*
X6260D01*
Y-302057D01*
X-54527D02*
X6260D01*
X-54527Y-331505D02*
Y-302057D01*
X-54528Y-278354D02*
X6260D01*
Y-248905D01*
X-54528D02*
X6260D01*
X-54528Y-278354D02*
Y-248905D01*
Y-225205D02*
X6260D01*
Y-195756D01*
X-54528D02*
X6260D01*
X-54528Y-225205D02*
Y-195756D01*
X-54527Y-172057D02*
X6260D01*
Y-142608D01*
X-54527D02*
X6260D01*
X-54527Y-172057D02*
Y-142608D01*
X12008Y-237008D02*
X29724D01*
X12008D02*
Y-226772D01*
X29724D01*
Y-237008D02*
Y-226772D01*
X12008Y-189370D02*
X29724D01*
X12008D02*
Y-179134D01*
X29724D01*
Y-189370D02*
Y-179134D01*
X12008Y-294094D02*
X29724D01*
X12008D02*
Y-283858D01*
X29724D01*
Y-294094D02*
Y-283858D01*
X11512Y-271063D02*
Y-254528D01*
X26473D01*
X11512Y-271063D02*
X26473D01*
Y-254528D01*
X11512Y-165600D02*
Y-149065D01*
X26473D01*
X11512Y-165600D02*
X26473D01*
Y-149065D01*
X6890Y-346850D02*
X24606D01*
X6890D02*
Y-336614D01*
X24606D01*
Y-346850D02*
Y-336614D01*
X11512Y-325197D02*
Y-308661D01*
X26473D01*
X11512Y-325197D02*
X26473D01*
Y-308661D01*
X-1575Y-343307D02*
X3937D01*
X-1575Y-333071D02*
X3937D01*
X-1575Y-343307D02*
Y-333071D01*
X3937Y-343307D02*
Y-333071D01*
X8661Y-228346D02*
X14173D01*
X8661Y-218110D02*
X14173D01*
X8661Y-228346D02*
Y-218110D01*
X14173Y-228346D02*
Y-218110D01*
X16929Y-283465D02*
Y-277953D01*
X6693Y-283465D02*
Y-277953D01*
Y-283465D02*
X16929D01*
X6693Y-277953D02*
X16929D01*
X7874Y-172835D02*
X18110D01*
X7874Y-178347D02*
X18110D01*
X7874D02*
Y-172835D01*
X18110Y-178347D02*
Y-172835D01*
D292*
X258519Y-123819D02*
X266393D01*
X258519Y-109646D02*
X266393D01*
X258519Y-123819D02*
Y-109646D01*
X266393Y-123819D02*
Y-109646D01*
X262456Y-118701D02*
Y-114764D01*
X260487Y-116732D02*
X264424D01*
X285827Y-276181D02*
Y-271063D01*
X295276Y-276181D02*
Y-271063D01*
X285827Y-276181D02*
X295276D01*
X285827Y-271063D02*
X295276D01*
X288681Y-273622D02*
X292421D01*
X290551Y-275492D02*
Y-271752D01*
X129134Y-349803D02*
Y-346260D01*
X136221Y-349803D02*
Y-346260D01*
X129134D02*
X136221D01*
X129134Y-349803D02*
X136221D01*
X131496Y-348031D02*
X133858D01*
X132677Y-349213D02*
Y-346850D01*
X129134Y-354134D02*
Y-350590D01*
X136221Y-354134D02*
Y-350590D01*
X129134D02*
X136221D01*
X129134Y-354134D02*
X136221D01*
X131496Y-352362D02*
X133858D01*
X132677Y-353543D02*
Y-351181D01*
X423961Y-357801D02*
Y-353864D01*
X421992Y-355832D02*
X425929D01*
X416874Y-361147D02*
X431047D01*
X416874Y-350517D02*
X431047D01*
Y-361147D02*
Y-350517D01*
X416874Y-361147D02*
Y-350517D01*
X468744Y-358588D02*
Y-354651D01*
X466776Y-356620D02*
X470713D01*
X461657Y-361935D02*
X475831D01*
X461657Y-351305D02*
X475831D01*
Y-361935D02*
Y-351305D01*
X461657Y-361935D02*
Y-351305D01*
X478291Y-360557D02*
Y-352683D01*
X492465Y-360557D02*
Y-352683D01*
X478291D02*
X492465D01*
X478291Y-360557D02*
X492465D01*
X483410Y-356620D02*
X487347D01*
X485378Y-358588D02*
Y-354651D01*
X433803Y-359769D02*
Y-351895D01*
X447976Y-359769D02*
Y-351895D01*
X433803D02*
X447976D01*
X433803Y-359769D02*
X447976D01*
X438921Y-355832D02*
X442858D01*
X440890Y-357801D02*
Y-353864D01*
X518189Y-360233D02*
Y-352359D01*
X532362Y-360233D02*
Y-352359D01*
X518189D02*
X532362D01*
X518189Y-360233D02*
X532362D01*
X523307Y-356296D02*
X527244D01*
X525276Y-358265D02*
Y-354328D01*
X562677Y-360627D02*
Y-352753D01*
X576850Y-360627D02*
Y-352753D01*
X562677D02*
X576850D01*
X562677Y-360627D02*
X576850D01*
X567795Y-356690D02*
X571732D01*
X569764Y-358659D02*
Y-354721D01*
X507165Y-358265D02*
Y-354328D01*
X505197Y-356296D02*
X509134D01*
X500079Y-361611D02*
X514252D01*
X500079Y-350981D02*
X514252D01*
Y-361611D02*
Y-350981D01*
X500079Y-361611D02*
Y-350981D01*
X552146Y-358068D02*
Y-354131D01*
X550177Y-356099D02*
X554114D01*
X545059Y-361414D02*
X559232D01*
X545059Y-350784D02*
X559232D01*
Y-361414D02*
Y-350784D01*
X545059Y-361414D02*
Y-350784D01*
X5709Y-190945D02*
Y-174803D01*
X-7837Y-190705D02*
Y-174705D01*
X618898Y-39370D02*
X622835D01*
X620866Y-41339D02*
Y-37402D01*
X624803Y-46457D02*
Y-32283D01*
X616929Y-46457D02*
Y-32283D01*
X624803D01*
X616929Y-46457D02*
X624803D01*
X-7837Y-295232D02*
Y-279232D01*
X5709Y-295472D02*
Y-279331D01*
X587992Y-33465D02*
X593110D01*
X587992Y-42913D02*
X593110D01*
Y-33465D01*
X587992Y-42913D02*
Y-33465D01*
X590551Y-40059D02*
Y-36319D01*
X588681Y-38189D02*
X592421D01*
X271472Y-384340D02*
X275410D01*
X271472Y-376860D02*
X275410D01*
Y-384340D02*
Y-376860D01*
X271472Y-384340D02*
Y-376860D01*
X273441Y-381781D02*
Y-379419D01*
X272260Y-380600D02*
X274622D01*
X205260D02*
X207622D01*
X206441Y-381781D02*
Y-379419D01*
X204472Y-384340D02*
Y-376860D01*
X208410Y-384340D02*
Y-376860D01*
X204472D02*
X208410D01*
X204472Y-384340D02*
X208410D01*
X208472D02*
X212409D01*
X208472Y-376860D02*
X212409D01*
Y-384340D02*
Y-376860D01*
X208472Y-384340D02*
Y-376860D01*
X210441Y-381781D02*
Y-379419D01*
X209260Y-380600D02*
X211622D01*
X217160D02*
X219522D01*
X218341Y-381781D02*
Y-379419D01*
X216372Y-384340D02*
Y-376860D01*
X220309Y-384340D02*
Y-376860D01*
X216372D02*
X220309D01*
X216372Y-384340D02*
X220309D01*
X220672D02*
X224609D01*
X220672Y-376860D02*
X224609D01*
Y-384340D02*
Y-376860D01*
X220672Y-384340D02*
Y-376860D01*
X222641Y-381781D02*
Y-379419D01*
X221460Y-380600D02*
X223822D01*
X235972Y-384340D02*
X239910D01*
X235972Y-376860D02*
X239910D01*
Y-384340D02*
Y-376860D01*
X235972Y-384340D02*
Y-376860D01*
X237941Y-381781D02*
Y-379419D01*
X236760Y-380600D02*
X239122D01*
X239972Y-384340D02*
X243910D01*
X239972Y-376860D02*
X243910D01*
Y-384340D02*
Y-376860D01*
X239972Y-384340D02*
Y-376860D01*
X241941Y-381781D02*
Y-379419D01*
X240760Y-380600D02*
X243122D01*
X251472Y-384340D02*
X255410D01*
X251472Y-376860D02*
X255410D01*
Y-384340D02*
Y-376860D01*
X251472Y-384340D02*
Y-376860D01*
X253441Y-381781D02*
Y-379419D01*
X252260Y-380600D02*
X254622D01*
X255760D02*
X258122D01*
X256941Y-381781D02*
Y-379419D01*
X254972Y-384340D02*
Y-376860D01*
X258910Y-384340D02*
Y-376860D01*
X254972D02*
X258910D01*
X254972Y-384340D02*
X258910D01*
X267472D02*
X271410D01*
X267472Y-376860D02*
X271410D01*
Y-384340D02*
Y-376860D01*
X267472Y-384340D02*
Y-376860D01*
X269441Y-381781D02*
Y-379419D01*
X268260Y-380600D02*
X270622D01*
M02*
